# BASEBOARD_FAB2 (Tioga Pass) — schematic netlist excerpt (pin names and nets, part order shuffled) for the footprints in the layout excerpt that follows; sources: Cadence DE-HDL packaged netlist, KiCad conversion of Wiwynn_Tioga_Pass_MB.brd

R25W14  120R2F-GP  1%  pkg RCL_GP  page 151 : \1\ = GND ; \2\ = BMC_M_A2
R2N14  RES  1.00K 1% EMPTY  pkg 0402  page 125 : A = P3V3_STBY ; B = FM_USB_P0_EN_BOOT_BIOS_STRAP_N
R1R23  RES  2.21K 1% CHIP  pkg 0402  page 188 : A = P3V3_STBY ; B = SMB_PCH_MEZZ_LOM3_SCL

(kicad_pcb
	(version 20260206)
	(generator "pcbnew")
	(generator_version "10.0")
	(general
		(thickness 1.6)
		(legacy_teardrops no)
	)
	(paper "A4")
	(title_block
		(title "Wiwynn_Tioga_Pass_MB.brd")
		(comment 1 "Tioga Pass / footprints 3516-3518 of 4770")
	)
	(layers
		(0 "F.Cu" signal "TOP")
		(4 "In1.Cu" signal "L2GND")
		(6 "In2.Cu" signal "L3")
		(8 "In3.Cu" signal "L4GND")
		(10 "In4.Cu" signal "L5")
		(12 "In5.Cu" signal "L6GND")
		(14 "In6.Cu" signal "L7VCC")
		(16 "In7.Cu" signal "L8VCC")
		(18 "In8.Cu" signal "L9GND")
		(20 "In9.Cu" signal "L10")
		(22 "In10.Cu" signal "L11GND")
		(24 "In11.Cu" signal "L12")
		(26 "In12.Cu" signal "L13GND")
		(2 "B.Cu" signal "BOTTOM")
		(9 "F.Adhes" user "F.Adhesive")
		(11 "B.Adhes" user "B.Adhesive")
		(13 "F.Paste" user "Package Geometry/Pastemask Top")
		(15 "B.Paste" user "Package Geometry/Pastemask Bottom")
		(5 "F.SilkS" user "Ref Des/Silkscreen Top")
		(7 "B.SilkS" user "Ref Des/Silkscreen Bottom")
		(1 "F.Mask" user "Board Geometry/Soldermask Top")
		(3 "B.Mask" user "Board Geometry/Soldermask Bottom")
		(17 "Dwgs.User" user "User.Drawings")
		(19 "Cmts.User" user "User.Comments")
		(21 "Eco1.User" user "User.Eco1")
		(23 "Eco2.User" user "User.Eco2")
		(25 "Edge.Cuts" user "Board Geometry/Outline")
		(27 "Margin" user)
		(31 "F.CrtYd" user "Package Geometry/Place Bound Top")
		(29 "B.CrtYd" user "Package Geometry/Place Bound Bottom")
		(35 "F.Fab" user "Ref Des/Assembly Top")
		(33 "B.Fab" user "Ref Des/Assembly Bottom")
	)
	(footprint ""
		(layer "B.Cu")
		(at 442.262006 -41.648126 180)
		(property "Reference" "R25W14"
			(at 0 0 0)
			(layer "B.SilkS")
			(hide yes)
			(effects
				(font
					(size 1.27 1.27)
				)
				(justify mirror)
			)
		)
		(property "Value" "*"
			(at -0.064008 -4.108196 180)
			(unlocked yes)
			(layer "B.Fab")
			(hide yes)
			(effects
				(font
					(size 1.27 1.016)
					(thickness 0.1524)
				)
				(justify mirror)
			)
		)
		(property "Device Type" "120R2F-GP_RCL_GP-120R2F-GP,64.A"
			(at -0.064008 -5.632196 180)
			(unlocked yes)
			(layer "B.Fab")
			(hide yes)
			(effects
				(font
					(size 1.27 1.016)
					(thickness 0.1524)
				)
				(justify mirror)
			)
		)
		(duplicate_pad_numbers_are_jumpers no)
		(fp_line
			(start 0.508 -0.9398)
			(end 0.508 0.9398)
			(stroke
				(width 0.1524)
				(type default)
			)
			(layer "B.SilkS")
		)
		(fp_line
			(start -0.508 -0.9398)
			(end 0.508 -0.9398)
			(stroke
				(width 0.1524)
				(type default)
			)
			(layer "B.SilkS")
		)
		(fp_rect
			(start 0.508 0.9398)
			(end -0.508 -0.9398)
			(stroke
				(width 0)
				(type default)
			)
			(fill no)
			(layer "B.CrtYd")
		)
		(fp_rect
			(start 0.508 0.9398)
			(end -0.508 -0.9398)
			(stroke
				(width 0)
				(type default)
			)
			(fill no)
			(layer "B.Fab")
		)
		(pad "1" smd custom
			(at 0 -0.4445)
			(size 0.1397 0.1397)
			(layers "B.Cu" "B.Mask" "B.Paste")
			(net "GND")
			(options
				(clearance outline)
				(anchor circle)
			)
			(primitives
				(gr_poly
					(pts
						(arc
							(start -0.1778 0.2794)
							(mid -0.249642 0.249642)
							(end -0.2794 0.1778)
						)
						(arc
							(start -0.2794 -0.1778)
							(mid -0.249642 -0.249642)
							(end -0.1778 -0.2794)
						)
						(arc
							(start 0.1778 -0.2794)
							(mid 0.249642 -0.249642)
							(end 0.2794 -0.1778)
						)
						(arc
							(start 0.2794 0.1778)
							(mid 0.249642 0.249642)
							(end 0.1778 0.2794)
						)
					)
					(width 0)
					(fill yes)
				)
			)
		)
		(pad "2" smd custom
			(at 0 0.4445)
			(size 0.1397 0.1397)
			(layers "B.Cu" "B.Mask" "B.Paste")
			(net "BMC_M_A2")
			(options
				(clearance outline)
				(anchor circle)
			)
			(primitives
				(gr_poly
					(pts
						(arc
							(start -0.1778 0.2794)
							(mid -0.249642 0.249642)
							(end -0.2794 0.1778)
						)
						(arc
							(start -0.2794 -0.1778)
							(mid -0.249642 -0.249642)
							(end -0.1778 -0.2794)
						)
						(arc
							(start 0.1778 -0.2794)
							(mid 0.249642 -0.249642)
							(end 0.2794 -0.1778)
						)
						(arc
							(start 0.2794 0.1778)
							(mid 0.249642 0.249642)
							(end 0.1778 0.2794)
						)
					)
					(width 0)
					(fill yes)
				)
			)
		)
	)
	(footprint ""
		(layer "B.Cu")
		(at 470.027 -54.991 -90)
		(property "Reference" "R1R23"
			(at 0 0 90)
			(layer "B.SilkS")
			(hide yes)
			(effects
				(font
					(size 1.27 1.27)
				)
				(justify mirror)
			)
		)
		(property "Value" ""
			(at 0 0 90)
			(layer "B.Fab")
			(effects
				(font
					(size 1.27 1.27)
				)
				(justify mirror)
			)
		)
		(duplicate_pad_numbers_are_jumpers no)
		(fp_poly
			(pts
				(xy 0.2794 -0.1016) (xy -0.2794 -0.1016) (xy -0.2794 0.9906) (xy 0.2794 0.9906)
			)
			(stroke
				(width 0)
				(type default)
			)
			(fill no)
			(layer "B.CrtYd")
		)
		(fp_line
			(start -0.2794 0.9906)
			(end -0.2794 -0.1016)
			(stroke
				(width 0.1)
				(type default)
			)
			(layer "B.Fab")
		)
		(fp_line
			(start 0.2794 0.9906)
			(end -0.2794 0.9906)
			(stroke
				(width 0.1)
				(type default)
			)
			(layer "B.Fab")
		)
		(fp_line
			(start -0.2794 -0.1016)
			(end 0.2794 -0.1016)
			(stroke
				(width 0.1)
				(type default)
			)
			(layer "B.Fab")
		)
		(fp_line
			(start 0.2794 -0.1016)
			(end 0.2794 0.9906)
			(stroke
				(width 0.1)
				(type default)
			)
			(layer "B.Fab")
		)
		(pad "1" smd rect
			(at 0 0 90)
			(size 0.508 0.508)
			(layers "B.Cu" "B.Mask" "B.Paste")
			(net "P3V3_STBY")
		)
		(pad "2" smd rect
			(at 0 0.889 90)
			(size 0.508 0.508)
			(layers "B.Cu" "B.Mask" "B.Paste")
			(net "SMB_PCH_MEZZ_LOM3_SCL")
		)
		(zone
			(layer "B.Cu")
			(hatch none 0.5)
			(connect_pads
				(clearance 0)
			)
			(min_thickness 0.25)
			(keepout
				(tracks not_allowed)
				(vias allowed)
				(pads allowed)
				(copperpour not_allowed)
				(footprints allowed)
			)
			(placement
				(enabled no)
				(sheetname "")
			)
			(fill
				(thermal_gap 0.5)
				(thermal_bridge_width 0.5)
				(island_removal_mode 0)
			)
			(polygon
				(pts
					(xy 469.392 -54.737) (xy 469.392 -55.245) (xy 469.773 -55.245) (xy 469.773 -54.737)
				)
			)
		)
		(zone
			(layer "B.Cu")
			(hatch none 0.5)
			(connect_pads
				(clearance 0)
			)
			(min_thickness 0.25)
			(keepout
				(tracks allowed)
				(vias not_allowed)
				(pads allowed)
				(copperpour not_allowed)
				(footprints allowed)
			)
			(placement
				(enabled no)
				(sheetname "")
			)
			(fill
				(thermal_gap 0.5)
				(thermal_bridge_width 0.5)
				(island_removal_mode 0)
			)
			(polygon
				(pts
					(xy 469.773 -54.737) (xy 469.773 -55.245) (xy 469.392 -55.245) (xy 469.392 -54.737)
				)
			)
		)
	)
	(footprint ""
		(layer "B.Cu")
		(at 404.5585 -96.393 -90)
		(property "Reference" "R2N14"
			(at 0 0 90)
			(layer "B.SilkS")
			(hide yes)
			(effects
				(font
					(size 1.27 1.27)
				)
				(justify mirror)
			)
		)
		(property "Value" ""
			(at 0 0 90)
			(layer "B.Fab")
			(effects
				(font
					(size 1.27 1.27)
				)
				(justify mirror)
			)
		)
		(duplicate_pad_numbers_are_jumpers no)
		(fp_poly
			(pts
				(xy 0.2794 -0.1016) (xy -0.2794 -0.1016) (xy -0.2794 0.9906) (xy 0.2794 0.9906)
			)
			(stroke
				(width 0)
				(type default)
			)
			(fill no)
			(layer "B.CrtYd")
		)
		(fp_line
			(start -0.2794 0.9906)
			(end -0.2794 -0.1016)
			(stroke
				(width 0.1)
				(type default)
			)
			(layer "B.Fab")
		)
		(fp_line
			(start 0.2794 0.9906)
			(end -0.2794 0.9906)
			(stroke
				(width 0.1)
				(type default)
			)
			(layer "B.Fab")
		)
		(fp_line
			(start -0.2794 -0.1016)
			(end 0.2794 -0.1016)
			(stroke
				(width 0.1)
				(type default)
			)
			(layer "B.Fab")
		)
		(fp_line
			(start 0.2794 -0.1016)
			(end 0.2794 0.9906)
			(stroke
				(width 0.1)
				(type default)
			)
			(layer "B.Fab")
		)
		(pad "1" smd rect
			(at 0 0 90)
			(size 0.508 0.508)
			(layers "B.Cu" "B.Mask" "B.Paste")
			(net "P3V3_STBY")
		)
		(pad "2" smd rect
			(at 0 0.889 90)
			(size 0.508 0.508)
			(layers "B.Cu" "B.Mask" "B.Paste")
			(net "FM_USB_P0_EN_BOOT_BIOS_STRAP_N")
		)
		(zone
			(layer "B.Cu")
			(hatch none 0.5)
			(connect_pads
				(clearance 0)
			)
			(min_thickness 0.25)
			(keepout
				(tracks not_allowed)
				(vias allowed)
				(pads allowed)
				(copperpour not_allowed)
				(footprints allowed)
			)
			(placement
				(enabled no)
				(sheetname "")
			)
			(fill
				(thermal_gap 0.5)
				(thermal_bridge_width 0.5)
				(island_removal_mode 0)
			)
			(polygon
				(pts
					(xy 403.9235 -96.139) (xy 403.9235 -96.647) (xy 404.3045 -96.647) (xy 404.3045 -96.139)
				)
			)
		)
		(zone
			(layer "B.Cu")
			(hatch none 0.5)
			(connect_pads
				(clearance 0)
			)
			(min_thickness 0.25)
			(keepout
				(tracks allowed)
				(vias not_allowed)
				(pads allowed)
				(copperpour not_allowed)
				(footprints allowed)
			)
			(placement
				(enabled no)
				(sheetname "")
			)
			(fill
				(thermal_gap 0.5)
				(thermal_bridge_width 0.5)
				(island_removal_mode 0)
			)
			(polygon
				(pts
					(xy 404.3045 -96.139) (xy 404.3045 -96.647) (xy 403.9235 -96.647) (xy 403.9235 -96.139)
				)
			)
		)
	)
)
